(kicad_pcb
	(version 20241229)
	(generator "pcbnew")
	(generator_version "9.0")
	(general
		(thickness 1.6)
		(legacy_teardrops no)
	)
	(paper "A4")
	(title_block
		(title "OCuLink to PCIe adapter")
		(date "2025-06-18")
		(rev "1.0.0")
		(company "Antmicro Ltd")
		(comment 1 "www.antmicro.com")
		(comment 9 "footprints 78-81 of 159")
	)
	(layers
		(0 "F.Cu" signal)
		(4 "In1.Cu" signal)
		(6 "In2.Cu" signal)
		(2 "B.Cu" signal)
		(9 "F.Adhes" user "F.Adhesive")
		(11 "B.Adhes" user "B.Adhesive")
		(13 "F.Paste" user)
		(15 "B.Paste" user)
		(5 "F.SilkS" user "F.Silkscreen")
		(7 "B.SilkS" user "B.Silkscreen")
		(1 "F.Mask" user)
		(3 "B.Mask" user)
		(17 "Dwgs.User" user "User.Drawings")
		(19 "Cmts.User" user "User.Comments")
		(21 "Eco1.User" user "User.Eco1")
		(23 "Eco2.User" user "User.Eco2")
		(25 "Edge.Cuts" user)
		(27 "Margin" user)
		(31 "F.CrtYd" user "F.Courtyard")
		(29 "B.CrtYd" user "B.Courtyard")
		(35 "F.Fab" user)
		(33 "B.Fab" user)
	)
	(footprint "antmicro-footprints:R_0402_1005Metric"
		(layer "F.Cu")
		(at 120.5 129.8)
		(descr "Resistor SMD 0402")
		(tags "resistor SMD 0402")
		(property "Reference" "R59"
			(at -3.3 0.4 0)
			(layer "F.SilkS")
			(effects
				(font
					(size 0.7 0.7)
					(thickness 0.15)
				)
				(justify left bottom)
			)
		)
		(property "Value" "R_1k5_0402"
			(at -1.011843 1.772047 0)
			(layer "F.Fab")
			(effects
				(font
					(size 0.7 0.7)
					(thickness 0.15)
				)
				(justify left bottom)
			)
		)
		(property "Datasheet" "https://www.bourns.com/docs/product-datasheets/cr.pdf"
			(at 0 0 0)
			(layer "F.Fab")
			(hide yes)
			(effects
				(font
					(size 1.27 1.27)
					(thickness 0.15)
				)
			)
		)
		(property "Description" "SMD Chip Resistor, 1.5 kohm, ± 1%, 62.5 mW, 0402 [1005 Metric], Thick Film, General Purpose"
			(at 0 0 0)
			(layer "F.Fab")
			(hide yes)
			(effects
				(font
					(size 1.27 1.27)
					(thickness 0.15)
				)
			)
		)
		(property "MPN" "CR0402-FX-1501GLF"
			(at 0 0 0)
			(unlocked yes)
			(layer "F.Fab")
			(hide yes)
			(effects
				(font
					(size 1 1)
					(thickness 0.15)
				)
			)
		)
		(property "Manufacturer" "Bourns"
			(at 0 0 0)
			(unlocked yes)
			(layer "F.Fab")
			(hide yes)
			(effects
				(font
					(size 1 1)
					(thickness 0.15)
				)
			)
		)
		(property "License" "Apache-2.0"
			(at 0 0 0)
			(unlocked yes)
			(layer "F.Fab")
			(hide yes)
			(effects
				(font
					(size 1 1)
					(thickness 0.15)
				)
			)
		)
		(property "Author" "Antmicro"
			(at 0 0 0)
			(unlocked yes)
			(layer "F.Fab")
			(hide yes)
			(effects
				(font
					(size 1 1)
					(thickness 0.15)
				)
			)
		)
		(property "Val" "1k5"
			(at 0 0 0)
			(unlocked yes)
			(layer "F.Fab")
			(hide yes)
			(effects
				(font
					(size 1 1)
					(thickness 0.15)
				)
			)
		)
		(property "Tolerance" "1%"
			(at 0 0 0)
			(unlocked yes)
			(layer "F.Fab")
			(hide yes)
			(effects
				(font
					(size 1 1)
					(thickness 0.15)
				)
			)
		)
		(sheetname "/Power/")
		(sheetfile "power.kicad_sch")
		(attr smd)
		(fp_rect
			(start -0.925 -0.47)
			(end 0.925 0.47)
			(stroke
				(width 0.05)
				(type default)
			)
			(fill no)
			(layer "F.CrtYd")
		)
		(fp_rect
			(start -0.5 -0.25)
			(end 0.5 0.25)
			(stroke
				(width 0.15)
				(type solid)
			)
			(fill no)
			(layer "F.Fab")
		)
		(fp_text user "Author: Antmicro"
			(at -0.95 4.169 0)
			(layer "F.Fab")
			(effects
				(font
					(size 0.7 0.7)
					(thickness 0.15)
				)
				(justify left bottom)
			)
		)
		(fp_text user "License: Apache-2.0"
			(at -0.95 5.169 0)
			(layer "F.Fab")
			(effects
				(font
					(size 0.7 0.7)
					(thickness 0.15)
				)
				(justify left bottom)
			)
		)
		(fp_text user "${REFERENCE}"
			(at -0.95 3.168 0)
			(layer "F.Fab")
			(effects
				(font
					(size 0.7 0.7)
					(thickness 0.15)
				)
				(justify left bottom)
			)
		)
		(pad "1" smd roundrect
			(at -0.48 0)
			(size 0.59 0.64)
			(layers "F.Cu" "F.Mask" "F.Paste")
			(roundrect_rratio 0.25)
			(net 66 "GND")
			(pintype "passive")
		)
		(pad "2" smd roundrect
			(at 0.48 0)
			(size 0.59 0.64)
			(layers "F.Cu" "F.Mask" "F.Paste")
			(roundrect_rratio 0.25)
			(net 106 "/Power/3V3_EN")
			(pintype "passive")
		)
	)
	(footprint "antmicro-footprints:VSSOP-8_2.3x2mm_P0.5mm"
		(layer "F.Cu")
		(at 126.824999 149.054999 90)
		(property "Reference" "U6"
			(at 1.95 1.6 270)
			(layer "F.SilkS")
			(effects
				(font
					(size 0.7 0.7)
					(thickness 0.15)
				)
				(justify left bottom)
			)
		)
		(property "Value" "74AUP2G132"
			(at 0 2.258 90)
			(layer "F.Fab")
			(effects
				(font
					(size 0.7 0.7)
					(thickness 0.15)
				)
				(justify left bottom)
			)
		)
		(property "Datasheet" "https://assets.nexperia.com/documents/data-sheet/74AUP2G132.pdf"
			(at 0 0 90)
			(layer "F.Fab")
			(hide yes)
			(effects
				(font
					(size 1.27 1.27)
					(thickness 0.15)
				)
			)
		)
		(property "Description" "Low-power dual 2-input NAND Schmitt trigger"
			(at 0 0 90)
			(layer "F.Fab")
			(hide yes)
			(effects
				(font
					(size 1.27 1.27)
					(thickness 0.15)
				)
			)
		)
		(property "Manufacturer" "Nexperia"
			(at 0 0 90)
			(unlocked yes)
			(layer "F.Fab")
			(hide yes)
			(effects
				(font
					(size 1 1)
					(thickness 0.15)
				)
			)
		)
		(property "MPN" "74AUP2G132"
			(at 0 0 90)
			(unlocked yes)
			(layer "F.Fab")
			(hide yes)
			(effects
				(font
					(size 1 1)
					(thickness 0.15)
				)
			)
		)
		(property "Author" "Antmicro"
			(at 0 0 90)
			(unlocked yes)
			(layer "F.Fab")
			(hide yes)
			(effects
				(font
					(size 1 1)
					(thickness 0.15)
				)
			)
		)
		(property "License" "Apache-2.0"
			(at 0 0 90)
			(unlocked yes)
			(layer "F.Fab")
			(hide yes)
			(effects
				(font
					(size 1 1)
					(thickness 0.15)
				)
			)
		)
		(sheetname "/Power/")
		(sheetfile "power.kicad_sch")
		(attr smd)
		(fp_line
			(start -0.82 -0.992)
			(end 0.825 -0.992)
			(stroke
				(width 0.15)
				(type solid)
			)
			(layer "F.SilkS")
		)
		(fp_line
			(start 0.825 1.007)
			(end -0.82 1.007)
			(stroke
				(width 0.15)
				(type solid)
			)
			(layer "F.SilkS")
		)
		(fp_circle
			(center -1.402 -1.192)
			(end -1.352 -1.192)
			(stroke
				(width 0.15)
				(type solid)
			)
			(fill yes)
			(layer "F.SilkS")
		)
		(fp_rect
			(start 1.8 1.35)
			(end -1.8 -1.35)
			(stroke
				(width 0.05)
				(type solid)
			)
			(fill no)
			(layer "F.CrtYd")
		)
		(fp_line
			(start -0.7 -0.99)
			(end -1.14 -0.55)
			(stroke
				(width 0.15)
				(type solid)
			)
			(layer "F.Fab")
		)
		(fp_rect
			(start -1.147 -0.992)
			(end 1.151 1.007)
			(stroke
				(width 0.15)
				(type solid)
			)
			(fill no)
			(layer "F.Fab")
		)
		(fp_text user "${REFERENCE}"
			(at 0 0 90)
			(layer "F.Fab")
			(effects
				(font
					(size 0.7 0.7)
					(thickness 0.15)
				)
				(justify left bottom)
			)
		)
		(fp_text user "Author: Antmicro"
			(at -1.8 5.208 90)
			(layer "F.Fab")
			(effects
				(font
					(size 0.7 0.7)
					(thickness 0.15)
				)
				(justify left bottom)
			)
		)
		(fp_text user "License: Apache-2.0"
			(at -1.8 6.408 90)
			(layer "F.Fab")
			(effects
				(font
					(size 0.7 0.7)
					(thickness 0.15)
				)
				(justify left bottom)
			)
		)
		(pad "1" smd rect
			(at -1.372 -0.742 90)
			(size 0.75 0.4)
			(layers "F.Cu" "F.Mask" "F.Paste")
			(net 185 "/Power/~{PERST_CONN}")
			(pinfunction "1A")
			(pintype "input")
		)
		(pad "2" smd rect
			(at -1.372 -0.244 90)
			(size 0.75 0.3)
			(layers "F.Cu" "F.Mask" "F.Paste")
			(net 105 "/Power/3V3_PG")
			(pinfunction "1B")
			(pintype "input")
		)
		(pad "3" smd rect
			(at -1.372 0.256 90)
			(size 0.75 0.3)
			(layers "F.Cu" "F.Mask" "F.Paste")
			(net 177 "Net-(U6-2Y)")
			(pinfunction "2Y")
			(pintype "output")
		)
		(pad "4" smd rect
			(at -1.372 0.757 90)
			(size 0.75 0.4)
			(layers "F.Cu" "F.Mask" "F.Paste")
			(net 66 "GND")
			(pinfunction "GND")
			(pintype "power_in")
		)
		(pad "5" smd rect
			(at 1.377 0.757 90)
			(size 0.75 0.4)
			(layers "F.Cu" "F.Mask" "F.Paste")
			(net 181 "/Power/PERST")
			(pinfunction "2A")
			(pintype "input")
		)
		(pad "6" smd rect
			(at 1.377 0.256 90)
			(size 0.75 0.3)
			(layers "F.Cu" "F.Mask" "F.Paste")
			(net 181 "/Power/PERST")
			(pinfunction "2B")
			(pintype "input")
		)
		(pad "7" smd rect
			(at 1.377 -0.244 90)
			(size 0.75 0.3)
			(layers "F.Cu" "F.Mask" "F.Paste")
			(net 181 "/Power/PERST")
			(pinfunction "1Y")
			(pintype "output")
		)
		(pad "8" smd rect
			(at 1.377 -0.742 90)
			(size 0.75 0.4)
			(layers "F.Cu" "F.Mask" "F.Paste")
			(net 134 "+3V3")
			(pinfunction "VCC")
			(pintype "power_in")
		)
	)
	(footprint "antmicro-footprints:R_0402_1005Metric"
		(layer "F.Cu")
		(at 120.5 133.8 180)
		(descr "Resistor SMD 0402")
		(tags "resistor SMD 0402")
		(property "Reference" "R16"
			(at 3.3 0.4 180)
			(layer "F.SilkS")
			(effects
				(font
					(size 0.7 0.7)
					(thickness 0.15)
				)
				(justify left top)
			)
		)
		(property "Value" "R_10k_0402"
			(at -1.011843 1.772046 0)
			(layer "F.Fab")
			(effects
				(font
					(size 0.7 0.7)
					(thickness 0.15)
				)
				(justify right top)
			)
		)
		(property "Datasheet" "https://www.bourns.com/docs/product-datasheets/cr.pdf"
			(at 0 0 0)
			(layer "F.Fab")
			(hide yes)
			(effects
				(font
					(size 1.27 1.27)
					(thickness 0.15)
				)
			)
		)
		(property "Description" "SMD Chip Resistor, 10 kohm, ± 1%, 62.5 mW, 0402 [1005 Metric], Thick Film, General Purpose"
			(at 0 0 0)
			(layer "F.Fab")
			(hide yes)
			(effects
				(font
					(size 1.27 1.27)
					(thickness 0.15)
				)
			)
		)
		(property "MPN" "CR0402-FX-1002GLF"
			(at 0 0 180)
			(unlocked yes)
			(layer "F.Fab")
			(hide yes)
			(effects
				(font
					(size 1 1)
					(thickness 0.15)
				)
			)
		)
		(property "Manufacturer" "Bourns"
			(at 0 0 180)
			(unlocked yes)
			(layer "F.Fab")
			(hide yes)
			(effects
				(font
					(size 1 1)
					(thickness 0.15)
				)
			)
		)
		(property "License" "Apache-2.0"
			(at 0 0 180)
			(unlocked yes)
			(layer "F.Fab")
			(hide yes)
			(effects
				(font
					(size 1 1)
					(thickness 0.15)
				)
			)
		)
		(property "Author" "Antmicro"
			(at 0 0 180)
			(unlocked yes)
			(layer "F.Fab")
			(hide yes)
			(effects
				(font
					(size 1 1)
					(thickness 0.15)
				)
			)
		)
		(property "Val" "10k"
			(at 0 0 180)
			(unlocked yes)
			(layer "F.Fab")
			(hide yes)
			(effects
				(font
					(size 1 1)
					(thickness 0.15)
				)
			)
		)
		(property "Tolerance" "1%"
			(at 0 0 180)
			(unlocked yes)
			(layer "F.Fab")
			(hide yes)
			(effects
				(font
					(size 1 1)
					(thickness 0.15)
				)
			)
		)
		(sheetname "/Power/")
		(sheetfile "power.kicad_sch")
		(attr smd)
		(fp_rect
			(start -0.925 -0.47)
			(end 0.925 0.47)
			(stroke
				(width 0.05)
				(type default)
			)
			(fill no)
			(layer "F.CrtYd")
		)
		(fp_rect
			(start -0.5 -0.25)
			(end 0.5 0.25)
			(stroke
				(width 0.15)
				(type solid)
			)
			(fill no)
			(layer "F.Fab")
		)
		(fp_text user "Author: Antmicro"
			(at -0.95 4.169 0)
			(layer "F.Fab")
			(effects
				(font
					(size 0.7 0.7)
					(thickness 0.15)
				)
				(justify right top)
			)
		)
		(fp_text user "License: Apache-2.0"
			(at -0.949999 5.169 0)
			(layer "F.Fab")
			(effects
				(font
					(size 0.7 0.7)
					(thickness 0.15)
				)
				(justify right top)
			)
		)
		(fp_text user "${REFERENCE}"
			(at 0 0 0)
			(layer "F.Fab")
			(effects
				(font
					(size 0.7 0.7)
					(thickness 0.15)
				)
				(justify right top)
			)
		)
		(pad "1" smd roundrect
			(at -0.48 0 180)
			(size 0.59 0.64)
			(layers "F.Cu" "F.Mask" "F.Paste")
			(roundrect_rratio 0.25)
			(net 107 "/Power/3V3_MODE")
			(pintype "passive")
		)
		(pad "2" smd roundrect
			(at 0.48 0 180)
			(size 0.59 0.64)
			(layers "F.Cu" "F.Mask" "F.Paste")
			(roundrect_rratio 0.25)
			(net 66 "GND")
			(pintype "passive")
		)
	)
	(footprint "antmicro-footprints:C_0402_1005Metric"
		(layer "F.Cu")
		(at 136.919998 106.35)
		(descr "Capacitor SMD 0402")
		(tags "capacitor SMD 0402")
		(property "Reference" "C32"
			(at 1.080002 0.45 180)
			(layer "F.SilkS")
			(effects
				(font
					(size 0.7 0.7)
					(thickness 0.15)
				)
				(justify left bottom)
			)
		)
		(property "Value" "C_100n_0402"
			(at -1.022927 2.155213 0)
			(layer "F.Fab")
			(effects
				(font
					(size 0.7 0.7)
					(thickness 0.15)
				)
				(justify left bottom)
			)
		)
		(property "Datasheet" "https://www.murata.com/products/productdetail?partno=GRM155R61H104KE14%23"
			(at 0 0 0)
			(layer "F.Fab")
			(hide yes)
			(effects
				(font
					(size 1.27 1.27)
					(thickness 0.15)
				)
			)
		)
		(property "Description" "SMD Multilayer Ceramic Capacitor, 0.1 µF, 50 V, 0402 [1005 Metric], ± 10%, X5R, GRM Series"
			(at 0 0 0)
			(layer "F.Fab")
			(hide yes)
			(effects
				(font
					(size 1.27 1.27)
					(thickness 0.15)
				)
			)
		)
		(property "MPN" "GRM155R61H104KE14D"
			(at 0 0 0)
			(unlocked yes)
			(layer "F.Fab")
			(hide yes)
			(effects
				(font
					(size 1 1)
					(thickness 0.15)
				)
			)
		)
		(property "Manufacturer" "Murata"
			(at 0 0 0)
			(unlocked yes)
			(layer "F.Fab")
			(hide yes)
			(effects
				(font
					(size 1 1)
					(thickness 0.15)
				)
			)
		)
		(property "License" "Apache-2.0"
			(at 0 0 0)
			(unlocked yes)
			(layer "F.Fab")
			(hide yes)
			(effects
				(font
					(size 1 1)
					(thickness 0.15)
				)
			)
		)
		(property "Author" "Antmicro"
			(at 0 0 0)
			(unlocked yes)
			(layer "F.Fab")
			(hide yes)
			(effects
				(font
					(size 1 1)
					(thickness 0.15)
				)
			)
		)
		(property "Val" "100n"
			(at 0 0 0)
			(unlocked yes)
			(layer "F.Fab")
			(hide yes)
			(effects
				(font
					(size 1 1)
					(thickness 0.15)
				)
			)
		)
		(property "Voltage" "50V"
			(at 0 0 0)
			(unlocked yes)
			(layer "F.Fab")
			(hide yes)
			(effects
				(font
					(size 1 1)
					(thickness 0.15)
				)
			)
		)
		(property "Dielectric" "X5R"
			(at 0 0 0)
			(unlocked yes)
			(layer "F.Fab")
			(hide yes)
			(effects
				(font
					(size 1 1)
					(thickness 0.15)
				)
			)
		)
		(sheetname "/Power/Ideal-diode-0/")
		(sheetfile "ideal-diode.kicad_sch")
		(attr smd)
		(fp_rect
			(start -0.925 -0.47)
			(end 0.925 0.47)
			(stroke
				(width 0.05)
				(type default)
			)
			(fill no)
			(layer "F.CrtYd")
		)
		(fp_line
			(start -0.494 -0.25)
			(end 0.504 -0.25)
			(stroke
				(width 0.15)
				(type solid)
			)
			(layer "F.Fab")
		)
		(fp_line
			(start -0.494 0.248)
			(end -0.494 -0.25)
			(stroke
				(width 0.15)
				(type solid)
			)
			(layer "F.Fab")
		)
		(fp_line
			(start 0.504 -0.25)
			(end 0.504 0.248)
			(stroke
				(width 0.15)
				(type solid)
			)
			(layer "F.Fab")
		)
		(fp_line
			(start 0.504 0.248)
			(end -0.494 0.248)
			(stroke
				(width 0.15)
				(type solid)
			)
			(layer "F.Fab")
		)
		(fp_text user "Author: Antmicro"
			(at -0.939 3.399 0)
			(layer "F.Fab")
			(effects
				(font
					(size 0.7 0.7)
					(thickness 0.15)
				)
				(justify left bottom)
			)
		)
		(fp_text user "License: Apache-2.0"
			(at -0.939 5.799 0)
			(layer "F.Fab")
			(effects
				(font
					(size 0.7 0.7)
					(thickness 0.15)
				)
				(justify left bottom)
			)
		)
		(fp_text user "${REFERENCE}"
			(at 0 0 0)
			(layer "F.Fab")
			(effects
				(font
					(size 0.7 0.7)
					(thickness 0.15)
				)
				(justify left bottom)
			)
		)
		(pad "1" smd roundrect
			(at -0.48 0)
			(size 0.59 0.64)
			(layers "F.Cu" "F.Mask" "F.Paste")
			(roundrect_rratio 0.25)
			(net 66 "GND")
			(pintype "passive")
		)
		(pad "2" smd roundrect
			(at 0.48 0)
			(size 0.59 0.64)
			(layers "F.Cu" "F.Mask" "F.Paste")
			(roundrect_rratio 0.25)
			(net 119 "/Power/VCC_PD")
			(pintype "passive")
		)
	)
)
